(kicad_pcb
	(version 20260206)
	(generator "pcbnew")
	(generator_version "10.0")
	(general
		(thickness 1.6)
		(legacy_teardrops no)
	)
	(paper "A4")
	(title_block
		(title "Wiwynn_Tioga_Pass_MB.brd")
		(comment 1 "Tioga Pass / footprints 3737-3743 of 4770")
	)
	(layers
		(0 "F.Cu" signal "TOP")
		(4 "In1.Cu" signal "L2GND")
		(6 "In2.Cu" signal "L3")
		(8 "In3.Cu" signal "L4GND")
		(10 "In4.Cu" signal "L5")
		(12 "In5.Cu" signal "L6GND")
		(14 "In6.Cu" signal "L7VCC")
		(16 "In7.Cu" signal "L8VCC")
		(18 "In8.Cu" signal "L9GND")
		(20 "In9.Cu" signal "L10")
		(22 "In10.Cu" signal "L11GND")
		(24 "In11.Cu" signal "L12")
		(26 "In12.Cu" signal "L13GND")
		(2 "B.Cu" signal "BOTTOM")
		(9 "F.Adhes" user "F.Adhesive")
		(11 "B.Adhes" user "B.Adhesive")
		(13 "F.Paste" user "Package Geometry/Pastemask Top")
		(15 "B.Paste" user "Package Geometry/Pastemask Bottom")
		(5 "F.SilkS" user "Ref Des/Silkscreen Top")
		(7 "B.SilkS" user "Ref Des/Silkscreen Bottom")
		(1 "F.Mask" user "Board Geometry/Soldermask Top")
		(3 "B.Mask" user "Board Geometry/Soldermask Bottom")
		(17 "Dwgs.User" user "User.Drawings")
		(19 "Cmts.User" user "User.Comments")
		(21 "Eco1.User" user "User.Eco1")
		(23 "Eco2.User" user "User.Eco2")
		(25 "Edge.Cuts" user "Board Geometry/Outline")
		(27 "Margin" user)
		(31 "F.CrtYd" user "Package Geometry/Place Bound Top")
		(29 "B.CrtYd" user "Package Geometry/Place Bound Bottom")
		(35 "F.Fab" user "Ref Des/Assembly Top")
		(33 "B.Fab" user "Ref Des/Assembly Bottom")
	)
	(footprint ""
		(layer "B.Cu")
		(at 374.84177 -95.568516 90)
		(property "Reference" "R7W19"
			(at 0.8382 -0.67818 90)
			(unlocked yes)
			(layer "B.SilkS")
			(effects
				(font
					(size 0.4064 0.254)
					(thickness 0.1524)
				)
				(justify left mirror)
			)
		)
		(property "Value" ""
			(at 0 0 90)
			(layer "B.Fab")
			(effects
				(font
					(size 1.27 1.27)
				)
				(justify mirror)
			)
		)
		(duplicate_pad_numbers_are_jumpers no)
		(fp_poly
			(pts
				(xy 0.2794 -0.1016) (xy -0.2794 -0.1016) (xy -0.2794 0.9906) (xy 0.2794 0.9906)
			)
			(stroke
				(width 0)
				(type default)
			)
			(fill no)
			(layer "B.CrtYd")
		)
		(fp_line
			(start 0.2794 -0.1016)
			(end 0.2794 0.9906)
			(stroke
				(width 0.1)
				(type default)
			)
			(layer "B.Fab")
		)
		(fp_line
			(start -0.2794 -0.1016)
			(end 0.2794 -0.1016)
			(stroke
				(width 0.1)
				(type default)
			)
			(layer "B.Fab")
		)
		(fp_line
			(start 0.2794 0.9906)
			(end -0.2794 0.9906)
			(stroke
				(width 0.1)
				(type default)
			)
			(layer "B.Fab")
		)
		(fp_line
			(start -0.2794 0.9906)
			(end -0.2794 -0.1016)
			(stroke
				(width 0.1)
				(type default)
			)
			(layer "B.Fab")
		)
		(pad "1" smd rect
			(at 0 0 270)
			(size 0.508 0.508)
			(layers "B.Cu" "B.Mask" "B.Paste")
			(net "P3V3_STBY")
		)
		(pad "2" smd rect
			(at 0 0.889 270)
			(size 0.508 0.508)
			(layers "B.Cu" "B.Mask" "B.Paste")
			(net "FM_BATTERY_SENSE_EN_R_N")
		)
		(zone
			(layer "B.Cu")
			(hatch none 0.5)
			(connect_pads
				(clearance 0)
			)
			(min_thickness 0.25)
			(keepout
				(tracks allowed)
				(vias not_allowed)
				(pads allowed)
				(copperpour not_allowed)
				(footprints allowed)
			)
			(placement
				(enabled no)
				(sheetname "")
			)
			(fill
				(thermal_gap 0.5)
				(thermal_bridge_width 0.5)
				(island_removal_mode 0)
			)
			(polygon
				(pts
					(xy 375.09577 -95.822516) (xy 375.09577 -95.314516) (xy 375.47677 -95.314516) (xy 375.47677 -95.822516)
				)
			)
		)
		(zone
			(layer "B.Cu")
			(hatch none 0.5)
			(connect_pads
				(clearance 0)
			)
			(min_thickness 0.25)
			(keepout
				(tracks not_allowed)
				(vias allowed)
				(pads allowed)
				(copperpour not_allowed)
				(footprints allowed)
			)
			(placement
				(enabled no)
				(sheetname "")
			)
			(fill
				(thermal_gap 0.5)
				(thermal_bridge_width 0.5)
				(island_removal_mode 0)
			)
			(polygon
				(pts
					(xy 375.47677 -95.822516) (xy 375.47677 -95.314516) (xy 375.09577 -95.314516) (xy 375.09577 -95.822516)
				)
			)
		)
	)
	(footprint ""
		(layer "B.Cu")
		(at 442.8871 -20.8788)
		(property "Reference" "Q9W2"
			(at 0.229362 -1.2065 0)
			(unlocked yes)
			(layer "B.SilkS")
			(effects
				(font
					(size 0.4064 0.254)
					(thickness 0.1524)
				)
				(justify left mirror)
			)
		)
		(property "Value" ""
			(at 0 0 0)
			(layer "B.Fab")
			(effects
				(font
					(size 1.27 1.27)
				)
				(justify mirror)
			)
		)
		(duplicate_pad_numbers_are_jumpers no)
		(fp_line
			(start -1.778 -0.5715)
			(end -1.778 0.3175)
			(stroke
				(width 0.1524)
				(type default)
			)
			(layer "B.SilkS")
		)
		(fp_line
			(start -1.778 2.4765)
			(end -1.778 1.5875)
			(stroke
				(width 0.1524)
				(type default)
			)
			(layer "B.SilkS")
		)
		(fp_line
			(start -0.9525 -0.5715)
			(end -1.778 -0.5715)
			(stroke
				(width 0.1524)
				(type default)
			)
			(layer "B.SilkS")
		)
		(fp_line
			(start -0.9525 2.4765)
			(end -1.778 2.4765)
			(stroke
				(width 0.1524)
				(type default)
			)
			(layer "B.SilkS")
		)
		(fp_line
			(start -0.381 0.635)
			(end -0.381 1.27)
			(stroke
				(width 0.1524)
				(type default)
			)
			(layer "B.SilkS")
		)
		(fp_circle
			(center 0.9525 -0.9271)
			(end 1.0795 -0.9271)
			(stroke
				(width 0.254)
				(type default)
			)
			(fill no)
			(layer "B.SilkS")
		)
		(fp_poly
			(pts
				(xy -1.778 2.4765) (xy -0.381 2.4765) (xy -0.381 -0.5715) (xy -1.778 -0.5715)
			)
			(stroke
				(width 0)
				(type default)
			)
			(fill no)
			(layer "B.CrtYd")
		)
		(fp_line
			(start -1.778 -0.5715)
			(end -0.381 -0.5715)
			(stroke
				(width 0.1)
				(type default)
			)
			(layer "B.Fab")
		)
		(fp_line
			(start -1.778 2.4765)
			(end -1.778 -0.5715)
			(stroke
				(width 0.1)
				(type default)
			)
			(layer "B.Fab")
		)
		(fp_line
			(start -0.381 -0.5715)
			(end -0.381 2.4765)
			(stroke
				(width 0.1)
				(type default)
			)
			(layer "B.Fab")
		)
		(fp_line
			(start -0.381 2.4765)
			(end -1.778 2.4765)
			(stroke
				(width 0.1)
				(type default)
			)
			(layer "B.Fab")
		)
		(fp_circle
			(center 0.9525 -0.9271)
			(end 1.0795 -0.9271)
			(stroke
				(width 0.254)
				(type default)
			)
			(fill no)
			(layer "B.Fab")
		)
		(pad "1" smd rect
			(at 0 0 180)
			(size 1.143 0.508)
			(layers "B.Cu" "B.Mask" "B.Paste")
			(net "FM_TPM_PRES_RST_N_R")
		)
		(pad "2" smd rect
			(at 0 1.905 180)
			(size 1.143 0.508)
			(layers "B.Cu" "B.Mask" "B.Paste")
			(net "GND")
		)
		(pad "3" smd rect
			(at -2.159 0.9525 180)
			(size 1.143 0.508)
			(layers "B.Cu" "B.Mask" "B.Paste")
			(net "FM_TPM_PRES_RST")
		)
	)
	(footprint ""
		(layer "B.Cu")
		(at 411.299914 -28.73756 90)
		(property "Reference" "C25W67"
			(at 0.8382 -0.67818 90)
			(unlocked yes)
			(layer "B.SilkS")
			(effects
				(font
					(size 0.4064 0.254)
					(thickness 0.1524)
				)
				(justify left mirror)
			)
		)
		(property "Value" ""
			(at 0 0 90)
			(layer "B.Fab")
			(effects
				(font
					(size 1.27 1.27)
				)
				(justify mirror)
			)
		)
		(duplicate_pad_numbers_are_jumpers no)
		(fp_poly
			(pts
				(xy -0.3048 -0.1016) (xy -0.3048 0.9906) (xy 0.3048 0.9906) (xy 0.3048 -0.1016)
			)
			(stroke
				(width 0)
				(type default)
			)
			(fill no)
			(layer "B.CrtYd")
		)
		(fp_line
			(start 0.3048 -0.1016)
			(end 0.3048 0.9906)
			(stroke
				(width 0.1)
				(type default)
			)
			(layer "B.Fab")
		)
		(fp_line
			(start -0.3048 -0.1016)
			(end 0.3048 -0.1016)
			(stroke
				(width 0.1)
				(type default)
			)
			(layer "B.Fab")
		)
		(fp_line
			(start 0.3048 0.9906)
			(end -0.3048 0.9906)
			(stroke
				(width 0.1)
				(type default)
			)
			(layer "B.Fab")
		)
		(fp_line
			(start -0.3048 0.9906)
			(end -0.3048 -0.1016)
			(stroke
				(width 0.1)
				(type default)
			)
			(layer "B.Fab")
		)
		(pad "1" smd rect
			(at 0 0 270)
			(size 0.508 0.508)
			(layers "B.Cu" "B.Mask" "B.Paste")
			(net "VCC_VA_3V3")
		)
		(pad "2" smd rect
			(at 0 0.889 270)
			(size 0.508 0.508)
			(layers "B.Cu" "B.Mask" "B.Paste")
			(net "GND")
		)
		(zone
			(layer "B.Cu")
			(hatch none 0.5)
			(connect_pads
				(clearance 0)
			)
			(min_thickness 0.25)
			(keepout
				(tracks allowed)
				(vias not_allowed)
				(pads allowed)
				(copperpour not_allowed)
				(footprints allowed)
			)
			(placement
				(enabled no)
				(sheetname "")
			)
			(fill
				(thermal_gap 0.5)
				(thermal_bridge_width 0.5)
				(island_removal_mode 0)
			)
			(polygon
				(pts
					(xy 411.553914 -28.99156) (xy 411.553914 -28.48356) (xy 411.934914 -28.48356) (xy 411.934914 -28.99156)
				)
			)
		)
		(zone
			(layer "B.Cu")
			(hatch none 0.5)
			(connect_pads
				(clearance 0)
			)
			(min_thickness 0.25)
			(keepout
				(tracks not_allowed)
				(vias allowed)
				(pads allowed)
				(copperpour not_allowed)
				(footprints allowed)
			)
			(placement
				(enabled no)
				(sheetname "")
			)
			(fill
				(thermal_gap 0.5)
				(thermal_bridge_width 0.5)
				(island_removal_mode 0)
			)
			(polygon
				(pts
					(xy 411.934914 -28.99156) (xy 411.934914 -28.48356) (xy 411.553914 -28.48356) (xy 411.553914 -28.99156)
				)
			)
		)
	)
	(footprint ""
		(layer "B.Cu")
		(at 80.731868 -12.954 -90)
		(property "Reference" "C5G79"
			(at -1.14681 0.76708 0)
			(unlocked yes)
			(layer "B.SilkS")
			(effects
				(font
					(size 0.7874 0.5842)
					(thickness 0.1524)
				)
				(justify mirror)
			)
		)
		(property "Value" ""
			(at 0 0 90)
			(layer "B.Fab")
			(effects
				(font
					(size 1.27 1.27)
				)
				(justify mirror)
			)
		)
		(duplicate_pad_numbers_are_jumpers no)
		(fp_rect
			(start 0.4953 1.6002)
			(end -0.4953 -0.2032)
			(stroke
				(width 0)
				(type default)
			)
			(fill no)
			(layer "B.CrtYd")
		)
		(fp_line
			(start -0.4953 1.6002)
			(end 0.4953 1.6002)
			(stroke
				(width 0.1)
				(type default)
			)
			(layer "B.Fab")
		)
		(fp_line
			(start 0.4953 1.6002)
			(end 0.4953 -0.2032)
			(stroke
				(width 0.1)
				(type default)
			)
			(layer "B.Fab")
		)
		(fp_line
			(start -0.4953 -0.2032)
			(end -0.4953 1.6002)
			(stroke
				(width 0.1)
				(type default)
			)
			(layer "B.Fab")
		)
		(fp_line
			(start 0.4953 -0.2032)
			(end -0.4953 -0.2032)
			(stroke
				(width 0.1)
				(type default)
			)
			(layer "B.Fab")
		)
		(pad "1" smd rect
			(at 0 0 90)
			(size 0.762 0.889)
			(layers "B.Cu" "B.Mask" "B.Paste")
			(net "PVDDQ_GHJ")
		)
		(pad "2" smd rect
			(at 0 1.397 90)
			(size 0.762 0.889)
			(layers "B.Cu" "B.Mask" "B.Paste")
			(net "GND")
		)
		(zone
			(layer "B.Cu")
			(hatch none 0.5)
			(connect_pads
				(clearance 0)
			)
			(min_thickness 0.25)
			(keepout
				(tracks not_allowed)
				(vias allowed)
				(pads allowed)
				(copperpour not_allowed)
				(footprints allowed)
			)
			(placement
				(enabled no)
				(sheetname "")
			)
			(fill
				(thermal_gap 0.5)
				(thermal_bridge_width 0.5)
				(island_removal_mode 0)
			)
			(polygon
				(pts
					(xy 79.779368 -12.573) (xy 80.287368 -12.573) (xy 80.287368 -13.335) (xy 79.779368 -13.335)
				)
			)
		)
	)
	(footprint ""
		(layer "B.Cu")
		(at 111.7727 -28.88234 90)
		(property "Reference" "C8T4"
			(at 0 0 90)
			(layer "B.SilkS")
			(hide yes)
			(effects
				(font
					(size 1.27 1.27)
				)
				(justify mirror)
			)
		)
		(property "Value" ""
			(at 0 0 90)
			(layer "B.Fab")
			(effects
				(font
					(size 1.27 1.27)
				)
				(justify mirror)
			)
		)
		(duplicate_pad_numbers_are_jumpers no)
		(fp_rect
			(start 0.500126 1.598422)
			(end -0.500126 -0.201422)
			(stroke
				(width 0)
				(type default)
			)
			(fill no)
			(layer "B.CrtYd")
		)
		(fp_line
			(start 0.500126 -0.201422)
			(end -0.500126 -0.201422)
			(stroke
				(width 0.1)
				(type default)
			)
			(layer "B.Fab")
		)
		(fp_line
			(start -0.500126 -0.201422)
			(end -0.500126 1.598422)
			(stroke
				(width 0.1)
				(type default)
			)
			(layer "B.Fab")
		)
		(fp_line
			(start 0.500126 1.598422)
			(end 0.500126 -0.201422)
			(stroke
				(width 0.1)
				(type default)
			)
			(layer "B.Fab")
		)
		(fp_line
			(start -0.500126 1.598422)
			(end 0.500126 1.598422)
			(stroke
				(width 0.1)
				(type default)
			)
			(layer "B.Fab")
		)
		(pad "1" smd rect
			(at 0 0)
			(size 0.889 0.9906)
			(layers "B.Cu" "B.Mask" "B.Paste")
			(net "PVDDQ_GHJ")
		)
		(pad "2" smd rect
			(at 0 1.397)
			(size 0.889 0.9906)
			(layers "B.Cu" "B.Mask" "B.Paste")
			(net "GND")
		)
		(zone
			(layer "B.Cu")
			(hatch none 0.5)
			(connect_pads
				(clearance 0)
			)
			(min_thickness 0.25)
			(keepout
				(tracks allowed)
				(vias not_allowed)
				(pads allowed)
				(copperpour not_allowed)
				(footprints allowed)
			)
			(placement
				(enabled no)
				(sheetname "")
			)
			(fill
				(thermal_gap 0.5)
				(thermal_bridge_width 0.5)
				(island_removal_mode 0)
			)
			(polygon
				(pts
					(xy 112.7252 -29.37764) (xy 112.2172 -29.37764) (xy 112.2172 -28.38704) (xy 112.7252 -28.38704)
				)
			)
		)
		(zone
			(layer "B.Cu")
			(hatch none 0.5)
			(connect_pads
				(clearance 0)
			)
			(min_thickness 0.25)
			(keepout
				(tracks not_allowed)
				(vias allowed)
				(pads allowed)
				(copperpour not_allowed)
				(footprints allowed)
			)
			(placement
				(enabled no)
				(sheetname "")
			)
			(fill
				(thermal_gap 0.5)
				(thermal_bridge_width 0.5)
				(island_removal_mode 0)
			)
			(polygon
				(pts
					(xy 112.7252 -29.37764) (xy 112.2172 -29.37764) (xy 112.2172 -28.38704) (xy 112.7252 -28.38704)
				)
			)
		)
	)
	(footprint ""
		(layer "B.Cu")
		(at 88.392 -135.4074 90)
		(property "Reference" "C8M3"
			(at -1.848866 0.752348 90)
			(unlocked yes)
			(layer "B.SilkS")
			(effects
				(font
					(size 1.27 0.9652)
					(thickness 0.1524)
				)
				(justify mirror)
			)
		)
		(property "Value" ""
			(at 0 0 90)
			(layer "B.Fab")
			(effects
				(font
					(size 1.27 1.27)
				)
				(justify mirror)
			)
		)
		(duplicate_pad_numbers_are_jumpers no)
		(fp_rect
			(start 0.500126 1.598422)
			(end -0.500126 -0.201422)
			(stroke
				(width 0)
				(type default)
			)
			(fill no)
			(layer "B.CrtYd")
		)
		(fp_line
			(start 0.500126 -0.201422)
			(end -0.500126 -0.201422)
			(stroke
				(width 0.1)
				(type default)
			)
			(layer "B.Fab")
		)
		(fp_line
			(start -0.500126 -0.201422)
			(end -0.500126 1.598422)
			(stroke
				(width 0.1)
				(type default)
			)
			(layer "B.Fab")
		)
		(fp_line
			(start 0.500126 1.598422)
			(end 0.500126 -0.201422)
			(stroke
				(width 0.1)
				(type default)
			)
			(layer "B.Fab")
		)
		(fp_line
			(start -0.500126 1.598422)
			(end 0.500126 1.598422)
			(stroke
				(width 0.1)
				(type default)
			)
			(layer "B.Fab")
		)
		(pad "1" smd rect
			(at 0 0)
			(size 0.889 0.9906)
			(layers "B.Cu" "B.Mask" "B.Paste")
			(net "PVDDQ_KLM")
		)
		(pad "2" smd rect
			(at 0 1.397)
			(size 0.889 0.9906)
			(layers "B.Cu" "B.Mask" "B.Paste")
			(net "GND")
		)
		(zone
			(layer "B.Cu")
			(hatch none 0.5)
			(connect_pads
				(clearance 0)
			)
			(min_thickness 0.25)
			(keepout
				(tracks not_allowed)
				(vias allowed)
				(pads allowed)
				(copperpour not_allowed)
				(footprints allowed)
			)
			(placement
				(enabled no)
				(sheetname "")
			)
			(fill
				(thermal_gap 0.5)
				(thermal_bridge_width 0.5)
				(island_removal_mode 0)
			)
			(polygon
				(pts
					(xy 89.3445 -135.9027) (xy 88.8365 -135.9027) (xy 88.8365 -134.9121) (xy 89.3445 -134.9121)
				)
			)
		)
		(zone
			(layer "B.Cu")
			(hatch none 0.5)
			(connect_pads
				(clearance 0)
			)
			(min_thickness 0.25)
			(keepout
				(tracks allowed)
				(vias not_allowed)
				(pads allowed)
				(copperpour not_allowed)
				(footprints allowed)
			)
			(placement
				(enabled no)
				(sheetname "")
			)
			(fill
				(thermal_gap 0.5)
				(thermal_bridge_width 0.5)
				(island_removal_mode 0)
			)
			(polygon
				(pts
					(xy 89.3445 -135.9027) (xy 88.8365 -135.9027) (xy 88.8365 -134.9121) (xy 89.3445 -134.9121)
				)
			)
		)
	)
	(footprint ""
		(layer "B.Cu")
		(at 375.412 -134.8105)
		(property "Reference" "C3M20"
			(at 0 0 0)
			(layer "B.SilkS")
			(hide yes)
			(effects
				(font
					(size 1.27 1.27)
				)
				(justify mirror)
			)
		)
		(property "Value" ""
			(at 0 0 0)
			(layer "B.Fab")
			(effects
				(font
					(size 1.27 1.27)
				)
				(justify mirror)
			)
		)
		(duplicate_pad_numbers_are_jumpers no)
		(fp_poly
			(pts
				(xy -0.3048 -0.1016) (xy -0.3048 0.9906) (xy 0.3048 0.9906) (xy 0.3048 -0.1016)
			)
			(stroke
				(width 0)
				(type default)
			)
			(fill no)
			(layer "B.CrtYd")
		)
		(fp_line
			(start -0.3048 -0.1016)
			(end 0.3048 -0.1016)
			(stroke
				(width 0.1)
				(type default)
			)
			(layer "B.Fab")
		)
		(fp_line
			(start -0.3048 0.9906)
			(end -0.3048 -0.1016)
			(stroke
				(width 0.1)
				(type default)
			)
			(layer "B.Fab")
		)
		(fp_line
			(start 0.3048 -0.1016)
			(end 0.3048 0.9906)
			(stroke
				(width 0.1)
				(type default)
			)
			(layer "B.Fab")
		)
		(fp_line
			(start 0.3048 0.9906)
			(end -0.3048 0.9906)
			(stroke
				(width 0.1)
				(type default)
			)
			(layer "B.Fab")
		)
		(pad "1" smd rect
			(at 0 0 180)
			(size 0.508 0.508)
			(layers "B.Cu" "B.Mask" "B.Paste")
			(net "P1V05_PCH_STBY_VCCA_PLL0")
		)
		(pad "2" smd rect
			(at 0 0.889 180)
			(size 0.508 0.508)
			(layers "B.Cu" "B.Mask" "B.Paste")
			(net "GND")
		)
		(zone
			(layer "B.Cu")
			(hatch none 0.5)
			(connect_pads
				(clearance 0)
			)
			(min_thickness 0.25)
			(keepout
				(tracks allowed)
				(vias not_allowed)
				(pads allowed)
				(copperpour not_allowed)
				(footprints allowed)
			)
			(placement
				(enabled no)
				(sheetname "")
			)
			(fill
				(thermal_gap 0.5)
				(thermal_bridge_width 0.5)
				(island_removal_mode 0)
			)
			(polygon
				(pts
					(xy 375.666 -134.5565) (xy 375.158 -134.5565) (xy 375.158 -134.1755) (xy 375.666 -134.1755)
				)
			)
		)
		(zone
			(layer "B.Cu")
			(hatch none 0.5)
			(connect_pads
				(clearance 0)
			)
			(min_thickness 0.25)
			(keepout
				(tracks not_allowed)
				(vias allowed)
				(pads allowed)
				(copperpour not_allowed)
				(footprints allowed)
			)
			(placement
				(enabled no)
				(sheetname "")
			)
			(fill
				(thermal_gap 0.5)
				(thermal_bridge_width 0.5)
				(island_removal_mode 0)
			)
			(polygon
				(pts
					(xy 375.666 -134.1755) (xy 375.158 -134.1755) (xy 375.158 -134.5565) (xy 375.666 -134.5565)
				)
			)
		)
	)
)
